#ISCELL
  mstr_misc dns *
  *
#ISCELL
  pure_quanta quanta_title_block_c *
  *
#ISCELL
  standard offpage *
  page23_i1
#ISCELL
  logical_power universal_gnd *
  page23_i10
#CELL
  pure_quanta q_cap *
  page23_i11
#CELL
  pure_quanta q_cap *
  page23_i12
#ISCELL
  logical_power universal_power *
  page23_i13
#ISCELL
  standard offpage *
  page23_i14
#ISCELL
  standard offpage *
  page23_i143
#ISCELL
  standard offpage *
  page23_i144
#ISCELL
  standard offpage *
  page23_i145
#ISCELL
  standard offpage *
  page23_i146
#ISCELL
  standard offpage *
  page23_i147
#ISCELL
  standard offpage *
  page23_i148
#ISCELL
  standard offpage *
  page23_i149
#ISCELL
  standard offpage *
  page23_i15
#ISCELL
  logical_power universal_gnd *
  page23_i150
#CELL
  pure_quanta q_fuse *
  page23_i153
#ISCELL
  logical_power universal_power *
  page23_i154
#CELL
  pure_quanta dt1240e04lp7 *
  page23_i155
#CELL
  pure_quanta dt1240e04lp7 *
  page23_i156
#ISCELL
  logical_power universal_gnd *
  page23_i157
#ISCELL
  logical_power universal_gnd *
  page23_i158
#ISCELL
  standard offpage *
  page23_i16
#CELL
  pure_quanta schottky_12 *
  page23_i161
#CELL
  pure_quanta sconn13_502280130cv01 *
  page23_i165
#CELL
  pure_quanta q_inductor *
  page23_i166
#CELL
  pure_quanta q_inductor *
  page23_i167
#CELL
  pure_quanta q_inductor *
  page23_i168
#CELL
  pure_quanta q_cap *
  page23_i169
#ISCELL
  standard offpage *
  page23_i17
#CELL
  pure_quanta q_cap *
  page23_i170
#ISCELL
  standard offpage *
  page23_i18
#CELL
  pure_quanta q_res *
  page23_i19
#CELL
  pure_quanta mosfet_nch_dual *
  page23_i2
#ISCELL
  standard offpage *
  page23_i20
#ISCELL
  standard offpage *
  page23_i21
#ISCELL
  logical_power universal_power *
  page23_i22
#ISCELL
  standard offpage *
  page23_i23
#ISCELL
  logical_power universal_gnd *
  page23_i24
#CELL
  pure_quanta q_cap *
  page23_i25
#CELL
  pure_quanta q_cap *
  page23_i26
#CELL
  pure_quanta q_res *
  page23_i27
#ISCELL
  logical_power universal_power *
  page23_i28
#CELL
  pure_quanta q_cap *
  page23_i29
#ISCELL
  standard offpage *
  page23_i3
#ISCELL
  logical_power universal_gnd *
  page23_i31
#CELL
  pure_quanta 74hc1g126gw *
  page23_i32
#CELL
  pure_quanta 74hc1g126gw *
  page23_i33
#CELL
  pure_quanta q_res *
  page23_i34
#CELL
  pure_quanta q_res *
  page23_i39
#CELL
  pure_quanta q_res *
  page23_i40
#CELL
  pure_quanta schottky_ac *
  page23_i41
#CELL
  pure_quanta schottky_ac *
  page23_i42
#ISCELL
  logical_power universal_gnd *
  page23_i44
#CELL
  pure_quanta q_cap *
  page23_i45
#ISCELL
  logical_power universal_power *
  page23_i46
#ISCELL
  logical_power universal_power *
  page23_i47
#CELL
  pure_quanta q_res *
  page23_i50
#CELL
  pure_quanta q_res *
  page23_i51
#ISCELL
  logical_power universal_power *
  page23_i52
#ISCELL
  logical_power universal_gnd *
  page23_i53
#CELL
  pure_quanta q_cap *
  page23_i54
#CELL
  pure_quanta mosfet_nch_dual *
  page23_i56
#CELL
  pure_quanta q_res *
  page23_i57
#ISCELL
  logical_power universal_gnd *
  page23_i58
#CELL
  pure_quanta q_res *
  page23_i59
#CELL
  pure_quanta q_res *
  page23_i60
#CELL
  pure_quanta q_res *
  page23_i61
#CELL
  pure_quanta q_res *
  page23_i62
#ISCELL
  logical_power universal_power *
  page23_i63
#CELL
  pure_quanta q_res *
  page23_i64
#CELL
  pure_quanta q_res *
  page23_i65
#ISCELL
  standard offpage *
  page23_i66
#CELL
  pure_quanta q_cap *
  page23_i67
#CELL
  pure_quanta q_res *
  page23_i68
#ISCELL
  logical_power universal_power *
  page23_i71
#ISCELL
  logical_power universal_gnd *
  page23_i73
#CELL
  pure_quanta bza462a *
  page23_i74
#CELL
  pure_quanta q_res *
  page23_i75
#ISCELL
  logical_power universal_gnd *
  page23_i76
#CELL
  pure_quanta q_cap *
  page23_i77
#ISCELL
  logical_power universal_gnd *
  page23_i82
#CELL
  pure_quanta q_cap *
  page23_i83
#CELL
  pure_quanta q_cap *
  page23_i84
#ISCELL
  standard offpage *
  page23_i88
#ISCELL
  standard offpage *
  page23_i89
#ISCELL
  standard offpage *
  page23_i90
#ISCELL
  standard offpage *
  page23_i91
#ISCELL
  standard offpage *
  page23_i92
#ISCELL
  standard offpage *
  page23_i93
#ISCELL
  standard offpage *
  page23_i94
#ISCELL
  logical_power universal_power *
  page23_i97
#ISCELL
  logical_power universal_power *
  page23_i98
#CELL
  pure_quanta q_res *
  page23_i99
